FILE_TYPE = MULTI_PHYS_TABLE;
PART 'IR354XX'
{==============================================================================================================================================================================================================}
:VALUE        | PACK_TYPE | MATERIAL | PART_NUMBER     = EnvComp |  PART_NUMBER | JEDEC_TYPE        |  CLASS | DESCRIPTION                       | HEIGHT     | COMPONENT_TYPE | LPID  | SPEED_URL | Status |RPL| AML | Bus_Unit | Days;
{==============================================================================================================================================================================================================}
'IR35411'     | 'SM'      | 'IC'     | 'H73688-001'(!) = ''      | 'H73688-001' |'QFN21_24_20_45MA' |  'IC'  |'IC,LIN,DRVR,40,QFN,IR35411,FETDVR'| '0.039 IN' |'LCC'           |'3919' | 'http://speed.intel.com:8081/speed/module/pdm/item/pdm_item_detail_direct.asp?item_cde=H73688-001&item_rev=01&url_param=unused' | '' | '' | '' | '' | '' 
'IR35411'     | 'SM'      | 'EMPTY'  | 'H73688-001'(!) = ''      | 'H73688-001' |'QFN21_24_20_45MA' |  'IO'  |'IC,LIN,DRVR,40,QFN,IR35411,FETDVR'| '0.039 IN' |'LCC'           |'3919' | 'http://speed.intel.com:8081/speed/module/pdm/item/pdm_item_detail_direct.asp?item_cde=H73688-001&item_rev=01&url_param=unused' | '' | '' | '' | '' | '' 
'IR35412'     | 'SM'      | 'IC'     | 'H73684-001'(!) = ''      | 'H73684-001' |'QFN21_24_20_45MA' |  'IC'  |'IC,LIN,DRVR,40,QFN,IR35412,FETDVR'| '0.039 IN' |'LCC'           |'3919' | 'http://speed.intel.com:8081/speed/module/pdm/item/pdm_item_detail_direct.asp?item_cde=H73684-001&item_rev=01&url_param=unused' | '' | '' | '' | '' | '' 
'IR35412'     | 'SM'      | 'EMPTY'  | 'H73684-001'(!) = ''      | 'H73684-001' |'QFN21_24_20_45MA' |  'IO'  |'IC,LIN,DRVR,40,QFN,IR35412,FETDVR'| '0.039 IN' |'LCC'           |'3919' | 'http://speed.intel.com:8081/speed/module/pdm/item/pdm_item_detail_direct.asp?item_cde=H73684-001&item_rev=01&url_param=unused' | '' | '' | '' | '' | '' 
END_PART
END.
